(kicad_pcb
	(version 20241229)
	(generator "pcbnew")
	(generator_version "9.0")
	(general
		(thickness 1.711)
		(legacy_teardrops no)
	)
	(paper "A4")
	(title_block
		(title "Antmicro Baseboard for Jetson AGX Thor")
		(date "2026-02-18")
		(rev "1.1.0")
		(company "Antmicro Ltd")
		(comment 1 "www.antmicro.com")
		(comment 9 "footprints 1016-1021 of 1170")
	)
	(layers
		(0 "F.Cu" signal)
		(4 "In1.Cu" signal)
		(6 "In2.Cu" signal)
		(8 "In3.Cu" signal)
		(10 "In4.Cu" jumper)
		(12 "In5.Cu" signal)
		(14 "In6.Cu" signal)
		(16 "In7.Cu" signal)
		(18 "In8.Cu" signal)
		(2 "B.Cu" signal)
		(9 "F.Adhes" user "F.Adhesive")
		(11 "B.Adhes" user "B.Adhesive")
		(13 "F.Paste" user)
		(15 "B.Paste" user)
		(5 "F.SilkS" user "F.Silkscreen")
		(7 "B.SilkS" user "B.Silkscreen")
		(1 "F.Mask" user)
		(3 "B.Mask" user)
		(17 "Dwgs.User" user "User.Drawings")
		(19 "Cmts.User" user "User.Comments")
		(21 "Eco1.User" user "User.Eco1")
		(23 "Eco2.User" user "User.Eco2")
		(25 "Edge.Cuts" user)
		(27 "Margin" user)
		(31 "F.CrtYd" user "F.Courtyard")
		(29 "B.CrtYd" user "B.Courtyard")
		(35 "F.Fab" user)
		(33 "B.Fab" user)
	)
	(footprint "antmicro-footprints:Mech_M2_2242_H2.5mm"
		(layer "B.Cu")
		(at 159.46 129.51 90)
		(property "Reference" "A2"
			(at -0.001 12.11 90)
			(layer "B.SilkS")
			(hide yes)
			(effects
				(font
					(size 0.7 0.7)
					(thickness 0.15)
				)
				(justify left bottom mirror)
			)
		)
		(property "Value" "Mech_M2_2242_H2.5mm"
			(at -0.001 -6.857 90)
			(layer "B.Fab")
			(effects
				(font
					(size 0.7 0.7)
					(thickness 0.15)
				)
				(justify left bottom mirror)
			)
		)
		(property "Description" "Mechanical model for M2 2242 2.5mm module"
			(at 0 0 90)
			(layer "B.Fab")
			(hide yes)
			(effects
				(font
					(size 1.27 1.27)
					(thickness 0.15)
				)
				(justify mirror)
			)
		)
		(property "MPN" ""
			(at 0 0 270)
			(unlocked yes)
			(layer "B.Fab")
			(hide yes)
			(effects
				(font
					(size 1 1)
					(thickness 0.15)
				)
				(justify mirror)
			)
		)
		(property "Manufacturer" ""
			(at 0 0 270)
			(unlocked yes)
			(layer "B.Fab")
			(hide yes)
			(effects
				(font
					(size 1 1)
					(thickness 0.15)
				)
				(justify mirror)
			)
		)
		(property "Author" "Antmicro"
			(at 0 0 270)
			(unlocked yes)
			(layer "B.Fab")
			(hide yes)
			(effects
				(font
					(size 1 1)
					(thickness 0.15)
				)
				(justify mirror)
			)
		)
		(property "License" "Apache-2.0"
			(at 0 0 270)
			(unlocked yes)
			(layer "B.Fab")
			(hide yes)
			(effects
				(font
					(size 1 1)
					(thickness 0.15)
				)
				(justify mirror)
			)
		)
		(sheetname "/M.2/")
		(sheetfile "m2.kicad_sch")
		(attr through_hole exclude_from_pos_files exclude_from_bom allow_missing_courtyard
			dnp
		)
		(fp_text user "${REFERENCE}"
			(at -11 -66.248 90)
			(layer "B.Fab")
			(effects
				(font
					(size 0.7 0.7)
					(thickness 0.15)
				)
				(justify right top mirror)
			)
		)
		(fp_text user "License: Apache-2.0"
			(at -11 -68.65 90)
			(layer "B.Fab")
			(effects
				(font
					(size 0.7 0.7)
					(thickness 0.15)
				)
				(justify right top mirror)
			)
		)
		(fp_text user "Author: Antmicro"
			(at -11 -67.45 90)
			(layer "B.Fab")
			(effects
				(font
					(size 0.7 0.7)
					(thickness 0.15)
				)
				(justify right top mirror)
			)
		)
	)
	(footprint "antmicro-footprints:TP_SMD_0.75mm"
		(layer "B.Cu")
		(at 201.4 116.4 180)
		(property "Reference" "TP68"
			(at 0.4 0.6 90)
			(layer "B.SilkS")
			(effects
				(font
					(size 0.7 0.7)
					(thickness 0.15)
				)
				(justify right top mirror)
			)
		)
		(property "Value" "TP_0.75mm_SMD"
			(at 0 -1.2 180)
			(layer "B.Fab")
			(effects
				(font
					(size 0.7 0.7)
					(thickness 0.15)
				)
				(justify right top mirror)
			)
		)
		(property "Description" "SMT test point"
			(at 0 0 180)
			(layer "B.Fab")
			(hide yes)
			(effects
				(font
					(size 1.27 1.27)
					(thickness 0.15)
				)
				(justify mirror)
			)
		)
		(property "MPN" ""
			(at 0 0 0)
			(unlocked yes)
			(layer "B.Fab")
			(hide yes)
			(effects
				(font
					(size 1 1)
					(thickness 0.15)
				)
				(justify mirror)
			)
		)
		(property "Manufacturer" ""
			(at 0 0 0)
			(unlocked yes)
			(layer "B.Fab")
			(hide yes)
			(effects
				(font
					(size 1 1)
					(thickness 0.15)
				)
				(justify mirror)
			)
		)
		(property "Author" "Antmicro"
			(at 0 0 0)
			(unlocked yes)
			(layer "B.Fab")
			(hide yes)
			(effects
				(font
					(size 1 1)
					(thickness 0.15)
				)
				(justify mirror)
			)
		)
		(property "License" "Apache-2.0"
			(at 0 0 0)
			(unlocked yes)
			(layer "B.Fab")
			(hide yes)
			(effects
				(font
					(size 1 1)
					(thickness 0.15)
				)
				(justify mirror)
			)
		)
		(sheetname "/USB Hub/")
		(sheetfile "usb_hub.kicad_sch")
		(attr exclude_from_pos_files exclude_from_bom)
		(fp_circle
			(center 0 0)
			(end 0.475 0)
			(stroke
				(width 0.05)
				(type default)
			)
			(fill no)
			(layer "B.CrtYd")
		)
		(fp_text user "License: Apache-2.0"
			(at -0.4 -5.101 180)
			(layer "B.Fab")
			(effects
				(font
					(size 0.7 0.7)
					(thickness 0.15)
				)
				(justify right top mirror)
			)
		)
		(fp_text user "${REFERENCE}"
			(at -0.4 -2.7 180)
			(layer "B.Fab")
			(effects
				(font
					(size 0.7 0.7)
					(thickness 0.15)
				)
				(justify right top mirror)
			)
		)
		(fp_text user "Author: Antmicro"
			(at -0.4 -3.901 180)
			(layer "B.Fab")
			(effects
				(font
					(size 0.7 0.7)
					(thickness 0.15)
				)
				(justify right top mirror)
			)
		)
		(pad "1" smd circle
			(at 0 0 180)
			(size 0.75 0.75)
			(layers "B.Cu" "B.Mask")
			(net 1095 "/USB Hub/DP1_VCONN2")
			(pinfunction "1")
			(pintype "passive")
		)
	)
	(footprint "antmicro-footprints:TP_SMD_0.75mm"
		(layer "B.Cu")
		(at 137.7 82.65 90)
		(property "Reference" "TP33"
			(at -3.05 -1.2 90)
			(layer "B.SilkS")
			(effects
				(font
					(size 0.7 0.7)
					(thickness 0.15)
				)
				(justify right top mirror)
			)
		)
		(property "Value" "TP_0.75mm_SMD"
			(at 0 -1.2 90)
			(layer "B.Fab")
			(effects
				(font
					(size 0.7 0.7)
					(thickness 0.15)
				)
				(justify right top mirror)
			)
		)
		(property "Description" "SMT test point"
			(at 0 0 90)
			(layer "B.Fab")
			(hide yes)
			(effects
				(font
					(size 1.27 1.27)
					(thickness 0.15)
				)
				(justify mirror)
			)
		)
		(property "MPN" ""
			(at 0 0 270)
			(unlocked yes)
			(layer "B.Fab")
			(hide yes)
			(effects
				(font
					(size 1 1)
					(thickness 0.15)
				)
				(justify mirror)
			)
		)
		(property "Manufacturer" ""
			(at 0 0 270)
			(unlocked yes)
			(layer "B.Fab")
			(hide yes)
			(effects
				(font
					(size 1 1)
					(thickness 0.15)
				)
				(justify mirror)
			)
		)
		(property "Author" "Antmicro"
			(at 0 0 270)
			(unlocked yes)
			(layer "B.Fab")
			(hide yes)
			(effects
				(font
					(size 1 1)
					(thickness 0.15)
				)
				(justify mirror)
			)
		)
		(property "License" "Apache-2.0"
			(at 0 0 270)
			(unlocked yes)
			(layer "B.Fab")
			(hide yes)
			(effects
				(font
					(size 1 1)
					(thickness 0.15)
				)
				(justify mirror)
			)
		)
		(sheetname "/SoM_Power/")
		(sheetfile "som_power.kicad_sch")
		(attr exclude_from_pos_files exclude_from_bom)
		(fp_circle
			(center 0 0)
			(end 0.475 0)
			(stroke
				(width 0.05)
				(type default)
			)
			(fill no)
			(layer "B.CrtYd")
		)
		(fp_text user "${REFERENCE}"
			(at -0.4 -2.7 90)
			(layer "B.Fab")
			(effects
				(font
					(size 0.7 0.7)
					(thickness 0.15)
				)
				(justify right top mirror)
			)
		)
		(fp_text user "Author: Antmicro"
			(at -0.4 -3.901 90)
			(layer "B.Fab")
			(effects
				(font
					(size 0.7 0.7)
					(thickness 0.15)
				)
				(justify right top mirror)
			)
		)
		(fp_text user "License: Apache-2.0"
			(at -0.4 -5.101 90)
			(layer "B.Fab")
			(effects
				(font
					(size 0.7 0.7)
					(thickness 0.15)
				)
				(justify right top mirror)
			)
		)
		(pad "1" smd circle
			(at 0 0 90)
			(size 0.75 0.75)
			(layers "B.Cu" "B.Mask")
			(net 907 "Net-(J1A-GPIO39)")
			(pinfunction "1")
			(pintype "passive")
		)
	)
	(footprint "antmicro-footprints:R_0402_1005Metric"
		(layer "B.Cu")
		(at 124.6 105.8 180)
		(descr "Resistor SMD 0402")
		(tags "resistor SMD 0402")
		(property "Reference" "R209"
			(at -3.9 -0.4 0)
			(layer "B.SilkS")
			(effects
				(font
					(size 0.7 0.7)
					(thickness 0.15)
				)
				(justify left bottom mirror)
			)
		)
		(property "Value" "R_47k_0402"
			(at -1.011843 -1.772046 0)
			(layer "B.Fab")
			(effects
				(font
					(size 0.7 0.7)
					(thickness 0.15)
				)
				(justify left bottom mirror)
			)
		)
		(property "Datasheet" "https://www.bourns.com/docs/product-datasheets/cr.pdf"
			(at 0 0 0)
			(layer "B.Fab")
			(hide yes)
			(effects
				(font
					(size 1.27 1.27)
					(thickness 0.15)
				)
				(justify mirror)
			)
		)
		(property "Description" "SMD Chip Resistor, 47 kohm, ± 1%, 62.5 mW, 0402 [1005 Metric], Thick Film, General Purpose"
			(at 0 0 0)
			(layer "B.Fab")
			(hide yes)
			(effects
				(font
					(size 1.27 1.27)
					(thickness 0.15)
				)
				(justify mirror)
			)
		)
		(property "Manufacturer" "Bourns"
			(at 0 0 0)
			(unlocked yes)
			(layer "B.Fab")
			(hide yes)
			(effects
				(font
					(size 1 1)
					(thickness 0.15)
				)
				(justify mirror)
			)
		)
		(property "MPN" "CR0402-FX-4702GLF"
			(at 0 0 0)
			(unlocked yes)
			(layer "B.Fab")
			(hide yes)
			(effects
				(font
					(size 1 1)
					(thickness 0.15)
				)
				(justify mirror)
			)
		)
		(property "Val" "47k"
			(at 0 0 0)
			(unlocked yes)
			(layer "B.Fab")
			(hide yes)
			(effects
				(font
					(size 1 1)
					(thickness 0.15)
				)
				(justify mirror)
			)
		)
		(property "License" "Apache-2.0"
			(at 0 0 0)
			(unlocked yes)
			(layer "B.Fab")
			(hide yes)
			(effects
				(font
					(size 1 1)
					(thickness 0.15)
				)
				(justify mirror)
			)
		)
		(property "Author" "Antmicro"
			(at 0 0 0)
			(unlocked yes)
			(layer "B.Fab")
			(hide yes)
			(effects
				(font
					(size 1 1)
					(thickness 0.15)
				)
				(justify mirror)
			)
		)
		(property "Tolerance" "1%"
			(at 0 0 0)
			(unlocked yes)
			(layer "B.Fab")
			(hide yes)
			(effects
				(font
					(size 1 1)
					(thickness 0.15)
				)
				(justify mirror)
			)
		)
		(sheetname "/M.2/")
		(sheetfile "m2.kicad_sch")
		(attr smd exclude_from_pos_files exclude_from_bom dnp)
		(fp_poly
			(pts
				(xy -0.925 0.47) (xy 0.925 0.47) (xy 0.925 -0.47) (xy -0.925 -0.47)
			)
			(stroke
				(width 0.05)
				(type default)
			)
			(fill no)
			(layer "B.CrtYd")
		)
		(fp_poly
			(pts
				(xy -0.5 0.25) (xy 0.5 0.25) (xy 0.5 -0.25) (xy -0.5 -0.25)
			)
			(stroke
				(width 0.15)
				(type solid)
			)
			(fill no)
			(layer "B.Fab")
		)
		(fp_text user "License: Apache-2.0"
			(at -0.949999 -5.169 0)
			(layer "B.Fab")
			(effects
				(font
					(size 0.7 0.7)
					(thickness 0.15)
				)
				(justify left bottom mirror)
			)
		)
		(fp_text user "Author: Antmicro"
			(at -0.95 -4.169 0)
			(layer "B.Fab")
			(effects
				(font
					(size 0.7 0.7)
					(thickness 0.15)
				)
				(justify left bottom mirror)
			)
		)
		(fp_text user "${REFERENCE}"
			(at -0.95 -3.168 0)
			(layer "B.Fab")
			(effects
				(font
					(size 0.7 0.7)
					(thickness 0.15)
				)
				(justify left bottom mirror)
			)
		)
		(pad "1" smd roundrect
			(at -0.48 0 180)
			(size 0.59 0.64)
			(layers "B.Cu" "B.Mask" "B.Paste")
			(roundrect_rratio 0.25)
			(net 2 "+3V3")
			(pintype "passive")
		)
		(pad "2" smd roundrect
			(at 0.48 0 180)
			(size 0.59 0.64)
			(layers "B.Cu" "B.Mask" "B.Paste")
			(roundrect_rratio 0.25)
			(net 827 "/M.2/~{PERST_M}")
			(pintype "passive")
		)
	)
	(footprint "antmicro-footprints:C_0402_1005Metric"
		(layer "B.Cu")
		(at 178.37 93.1 180)
		(descr "Capacitor SMD 0402")
		(tags "capacitor SMD 0402")
		(property "Reference" "C38"
			(at -0.66 -1.48 0)
			(layer "B.SilkS")
			(effects
				(font
					(size 0.7 0.7)
					(thickness 0.15)
				)
				(justify left bottom mirror)
			)
		)
		(property "Value" "C_100n_0402"
			(at -1.022927 -2.155213 0)
			(layer "B.Fab")
			(effects
				(font
					(size 0.7 0.7)
					(thickness 0.15)
				)
				(justify left bottom mirror)
			)
		)
		(property "Datasheet" "https://www.murata.com/products/productdetail?partno=GRM155R61H104KE14%23"
			(at 0 0 0)
			(layer "B.Fab")
			(hide yes)
			(effects
				(font
					(size 1.27 1.27)
					(thickness 0.15)
				)
				(justify mirror)
			)
		)
		(property "Description" "SMD Multilayer Ceramic Capacitor, 0.1 µF, 50 V, 0402 [1005 Metric], ± 10%, X5R, GRM Series"
			(at 0 0 0)
			(layer "B.Fab")
			(hide yes)
			(effects
				(font
					(size 1.27 1.27)
					(thickness 0.15)
				)
				(justify mirror)
			)
		)
		(property "MPN" "GRM155R61H104KE14D"
			(at 0 0 0)
			(unlocked yes)
			(layer "B.Fab")
			(hide yes)
			(effects
				(font
					(size 1 1)
					(thickness 0.15)
				)
				(justify mirror)
			)
		)
		(property "Manufacturer" "Murata"
			(at 0 0 0)
			(unlocked yes)
			(layer "B.Fab")
			(hide yes)
			(effects
				(font
					(size 1 1)
					(thickness 0.15)
				)
				(justify mirror)
			)
		)
		(property "License" "Apache-2.0"
			(at 0 0 0)
			(unlocked yes)
			(layer "B.Fab")
			(hide yes)
			(effects
				(font
					(size 1 1)
					(thickness 0.15)
				)
				(justify mirror)
			)
		)
		(property "Author" "Antmicro"
			(at 0 0 0)
			(unlocked yes)
			(layer "B.Fab")
			(hide yes)
			(effects
				(font
					(size 1 1)
					(thickness 0.15)
				)
				(justify mirror)
			)
		)
		(property "Val" "100n"
			(at 0 0 0)
			(unlocked yes)
			(layer "B.Fab")
			(hide yes)
			(effects
				(font
					(size 1 1)
					(thickness 0.15)
				)
				(justify mirror)
			)
		)
		(property "Voltage" "50V"
			(at 0 0 0)
			(unlocked yes)
			(layer "B.Fab")
			(hide yes)
			(effects
				(font
					(size 1 1)
					(thickness 0.15)
				)
				(justify mirror)
			)
		)
		(property "Dielectric" "X5R"
			(at 0 0 0)
			(unlocked yes)
			(layer "B.Fab")
			(hide yes)
			(effects
				(font
					(size 1 1)
					(thickness 0.15)
				)
				(justify mirror)
			)
		)
		(property "Public" "False"
			(at 0 0 0)
			(unlocked yes)
			(layer "B.Fab")
			(hide yes)
			(effects
				(font
					(size 1 1)
					(thickness 0.15)
				)
				(justify mirror)
			)
		)
		(sheetname "/Power/")
		(sheetfile "power.kicad_sch")
		(attr smd exclude_from_pos_files exclude_from_bom dnp)
		(fp_rect
			(start -0.925 0.47)
			(end 0.925 -0.47)
			(stroke
				(width 0.05)
				(type default)
			)
			(fill no)
			(layer "B.CrtYd")
		)
		(fp_line
			(start 0.504 0.25)
			(end 0.504 -0.248)
			(stroke
				(width 0.15)
				(type solid)
			)
			(layer "B.Fab")
		)
		(fp_line
			(start 0.504 -0.248)
			(end -0.494 -0.248)
			(stroke
				(width 0.15)
				(type solid)
			)
			(layer "B.Fab")
		)
		(fp_line
			(start -0.494 0.25)
			(end 0.504 0.25)
			(stroke
				(width 0.15)
				(type solid)
			)
			(layer "B.Fab")
		)
		(fp_line
			(start -0.494 -0.248)
			(end -0.494 0.25)
			(stroke
				(width 0.15)
				(type solid)
			)
			(layer "B.Fab")
		)
		(fp_text user "License: Apache-2.0"
			(at -0.939 -5.799 0)
			(layer "B.Fab")
			(effects
				(font
					(size 0.7 0.7)
					(thickness 0.15)
				)
				(justify left bottom mirror)
			)
		)
		(fp_text user "Author: Antmicro"
			(at -0.939 -3.399 0)
			(layer "B.Fab")
			(effects
				(font
					(size 0.7 0.7)
					(thickness 0.15)
				)
				(justify left bottom mirror)
			)
		)
		(fp_text user "${REFERENCE}"
			(at -0.939 -4.599 0)
			(layer "B.Fab")
			(effects
				(font
					(size 0.7 0.7)
					(thickness 0.15)
				)
				(justify left bottom mirror)
			)
		)
		(pad "1" smd roundrect
			(at -0.48 0 180)
			(size 0.59 0.64)
			(layers "B.Cu" "B.Mask" "B.Paste")
			(roundrect_rratio 0.25)
			(net 1 "GND")
			(pintype "passive")
		)
		(pad "2" smd roundrect
			(at 0.48 0 180)
			(size 0.59 0.64)
			(layers "B.Cu" "B.Mask" "B.Paste")
			(roundrect_rratio 0.25)
			(net 522 "/Power/USBPD1_HV")
			(pintype "passive")
		)
	)
	(footprint "antmicro-footprints:R_0402_1005Metric"
		(layer "B.Cu")
		(at 215.93 95.1 90)
		(descr "Resistor SMD 0402")
		(tags "resistor SMD 0402")
		(property "Reference" "R227"
			(at -3.8 -0.35 90)
			(layer "B.SilkS")
			(effects
				(font
					(size 0.7 0.7)
					(thickness 0.15)
				)
				(justify right top mirror)
			)
		)
		(property "Value" "R_0R_0402"
			(at -1.011843 -1.772047 90)
			(layer "B.Fab")
			(effects
				(font
					(size 0.7 0.7)
					(thickness 0.15)
				)
				(justify right top mirror)
			)
		)
		(property "Datasheet" "https://industrial.panasonic.com/cdbs/www-data/pdf/RDA0000/AOA0000C301.pdf"
			(at 0 0 90)
			(layer "B.Fab")
			(hide yes)
			(effects
				(font
					(size 1.27 1.27)
					(thickness 0.15)
				)
				(justify mirror)
			)
		)
		(property "Description" "SMD Chip Resistor, Jumper, 0 ohm, 100 mW, 0402 [1005 Metric], Thick Film, General Purpose"
			(at 0 0 90)
			(layer "B.Fab")
			(hide yes)
			(effects
				(font
					(size 1.27 1.27)
					(thickness 0.15)
				)
				(justify mirror)
			)
		)
		(property "Manufacturer" "Panasonic"
			(at 0 0 270)
			(unlocked yes)
			(layer "B.Fab")
			(hide yes)
			(effects
				(font
					(size 1 1)
					(thickness 0.15)
				)
				(justify mirror)
			)
		)
		(property "MPN" "ERJ2GE0R00X"
			(at 0 0 270)
			(unlocked yes)
			(layer "B.Fab")
			(hide yes)
			(effects
				(font
					(size 1 1)
					(thickness 0.15)
				)
				(justify mirror)
			)
		)
		(property "Val" "0R"
			(at 0 0 270)
			(unlocked yes)
			(layer "B.Fab")
			(hide yes)
			(effects
				(font
					(size 1 1)
					(thickness 0.15)
				)
				(justify mirror)
			)
		)
		(property "License" "Apache-2.0"
			(at 0 0 270)
			(unlocked yes)
			(layer "B.Fab")
			(hide yes)
			(effects
				(font
					(size 1 1)
					(thickness 0.15)
				)
				(justify mirror)
			)
		)
		(property "Author" "Antmicro"
			(at 0 0 270)
			(unlocked yes)
			(layer "B.Fab")
			(hide yes)
			(effects
				(font
					(size 1 1)
					(thickness 0.15)
				)
				(justify mirror)
			)
		)
		(property "Tolerance" "~"
			(at 0 0 270)
			(unlocked yes)
			(layer "B.Fab")
			(hide yes)
			(effects
				(font
					(size 1 1)
					(thickness 0.15)
				)
				(justify mirror)
			)
		)
		(property "Current" "1A"
			(at 0 0 270)
			(unlocked yes)
			(layer "B.Fab")
			(hide yes)
			(effects
				(font
					(size 1 1)
					(thickness 0.15)
				)
				(justify mirror)
			)
		)
		(sheetname "/USB DP Alt mode/")
		(sheetfile "usb_dp.kicad_sch")
		(attr smd)
		(fp_rect
			(start -0.925 0.47)
			(end 0.925 -0.47)
			(stroke
				(width 0.05)
				(type default)
			)
			(fill no)
			(layer "B.CrtYd")
		)
		(fp_rect
			(start -0.5 0.25)
			(end 0.5 -0.25)
			(stroke
				(width 0.15)
				(type solid)
			)
			(fill no)
			(layer "B.Fab")
		)
		(fp_text user "Author: Antmicro"
			(at -0.95 -4.169 90)
			(layer "B.Fab")
			(effects
				(font
					(size 0.7 0.7)
					(thickness 0.15)
				)
				(justify right top mirror)
			)
		)
		(fp_text user "${REFERENCE}"
			(at -0.95 -3.168 90)
			(layer "B.Fab")
			(effects
				(font
					(size 0.7 0.7)
					(thickness 0.15)
				)
				(justify right top mirror)
			)
		)
		(fp_text user "License: Apache-2.0"
			(at -0.95 -5.169 90)
			(layer "B.Fab")
			(effects
				(font
					(size 0.7 0.7)
					(thickness 0.15)
				)
				(justify right top mirror)
			)
		)
		(pad "1" smd roundrect
			(at -0.48 0 90)
			(size 0.59 0.64)
			(layers "B.Cu" "B.Mask" "B.Paste")
			(roundrect_rratio 0.25)
			(net 948 "/USB DP Alt mode/USBC_HPD")
			(pintype "passive")
		)
		(pad "2" smd roundrect
			(at 0.48 0 90)
			(size 0.59 0.64)
			(layers "B.Cu" "B.Mask" "B.Paste")
			(roundrect_rratio 0.25)
			(net 957 "/USB DP Alt mode/HPDIN")
			(pintype "passive")
		)
	)
)
